(kicad_pcb
	(version 20260206)
	(generator "pcbnew")
	(generator_version "10.0")
	(general
		(thickness 1.6)
		(legacy_teardrops no)
	)
	(paper "A4")
	(title_block
		(title "01162023_DA0F0TEBIF0_F0T_Expander_BD_F_brd_V02_OCP.brd")
		(comment 1 "Grand Teton / footprints 6665-6671 of 9728")
	)
	(layers
		(0 "F.Cu" signal "TOP")
		(4 "In1.Cu" signal "GND")
		(6 "In2.Cu" signal "VCC")
		(8 "In3.Cu" signal "VCC1")
		(10 "In4.Cu" signal "GND1")
		(12 "In5.Cu" signal "IN1")
		(14 "In6.Cu" signal "GND2")
		(16 "In7.Cu" signal "IN2")
		(18 "In8.Cu" signal "GND3")
		(20 "In9.Cu" signal "IN3")
		(22 "In10.Cu" signal "GND4")
		(24 "In11.Cu" signal "IN4")
		(26 "In12.Cu" signal "GND5")
		(28 "In13.Cu" signal "IN5")
		(30 "In14.Cu" signal "GND6")
		(32 "In15.Cu" signal "IN6")
		(34 "In16.Cu" signal "GND7")
		(2 "B.Cu" signal "BOTTOM")
		(9 "F.Adhes" user "F.Adhesive")
		(11 "B.Adhes" user "B.Adhesive")
		(13 "F.Paste" user "Package Geometry/Pastemask Top")
		(15 "B.Paste" user "Package Geometry/Pastemask Bottom")
		(5 "F.SilkS" user "Ref Des/Silkscreen Top")
		(7 "B.SilkS" user "Ref Des/Silkscreen Bottom")
		(1 "F.Mask" user "Board Geometry/Soldermask Top")
		(3 "B.Mask" user "Board Geometry/Soldermask Bottom")
		(17 "Dwgs.User" user "User.Drawings")
		(19 "Cmts.User" user "User.Comments")
		(21 "Eco1.User" user "User.Eco1")
		(23 "Eco2.User" user "User.Eco2")
		(25 "Edge.Cuts" user "Board Geometry/Outline")
		(27 "Margin" user)
		(31 "F.CrtYd" user "Package Geometry/Place Bound Top")
		(29 "B.CrtYd" user "Package Geometry/Place Bound Bottom")
		(35 "F.Fab" user "Ref Des/Assembly Top")
		(33 "B.Fab" user "Ref Des/Assembly Bottom")
	)
	(footprint ""
		(layer "F.Cu")
		(at 16.041116 -115.695476)
		(property "Reference" "PU80"
			(at -2.425446 3.173476 90)
			(unlocked yes)
			(layer "F.SilkS")
			(effects
				(font
					(size 0.7874 0.5842)
					(thickness 0.1524)
				)
			)
		)
		(property "Value" ""
			(at 0 0 0)
			(layer "F.Fab")
			(effects
				(font
					(size 1.27 1.27)
				)
			)
		)
		(duplicate_pad_numbers_are_jumpers no)
		(fp_line
			(start -1.239774 -1.495298)
			(end 1.239774 -1.495298)
			(stroke
				(width 0.1524)
				(type default)
			)
			(layer "F.SilkS")
		)
		(fp_line
			(start -1.239774 1.495298)
			(end -1.239774 -1.495298)
			(stroke
				(width 0.1524)
				(type default)
			)
			(layer "F.SilkS")
		)
		(fp_line
			(start 1.239774 -1.495298)
			(end 1.239774 1.495298)
			(stroke
				(width 0.1524)
				(type default)
			)
			(layer "F.SilkS")
		)
		(fp_line
			(start 1.239774 1.495298)
			(end -1.239774 1.495298)
			(stroke
				(width 0.1524)
				(type default)
			)
			(layer "F.SilkS")
		)
		(fp_poly
			(pts
				(xy -1.713738 -1.75895) (xy -2.432304 -1.040638) (xy -1.354582 -0.681482)
			)
			(stroke
				(width 0)
				(type default)
			)
			(fill yes)
			(layer "F.SilkS")
		)
		(fp_line
			(start -0.8001 -1.050036)
			(end 0.8001 -1.050036)
			(stroke
				(width 0.1)
				(type default)
			)
			(layer "F.Fab")
		)
		(fp_line
			(start -0.8001 1.050036)
			(end -0.8001 -1.050036)
			(stroke
				(width 0.1)
				(type default)
			)
			(layer "F.Fab")
		)
		(fp_line
			(start 0.8001 -1.050036)
			(end 0.8001 1.050036)
			(stroke
				(width 0.1)
				(type default)
			)
			(layer "F.Fab")
		)
		(fp_line
			(start 0.8001 1.050036)
			(end -0.8001 1.050036)
			(stroke
				(width 0.1)
				(type default)
			)
			(layer "F.Fab")
		)
		(fp_poly
			(pts
				(xy -2.458974 -0.508) (xy -2.458974 0.508) (xy -1.442974 0)
			)
			(stroke
				(width 0)
				(type default)
			)
			(fill yes)
			(layer "F.Fab")
		)
		(pad "1_2" smd circle
			(at -0.374904 0 90)
			(size 0 0)
			(layers "F.Cu" "F.Mask" "F.Paste")
			(net "P3V3_AUX")
		)
		(pad "3" smd rect
			(at -0.499872 0.999998)
			(size 0.254 0.7112)
			(layers "F.Cu" "F.Mask" "F.Paste")
			(net "GND")
		)
		(pad "4" smd rect
			(at 0 0.999998)
			(size 0.254 0.7112)
			(layers "F.Cu" "F.Mask" "F.Paste")
			(net "P3V3_NIC0_CO_ILIMIT")
		)
		(pad "5" smd rect
			(at 0.499872 0.999998)
			(size 0.254 0.7112)
			(layers "F.Cu" "F.Mask" "F.Paste")
			(net "P3V3_NIC0_CO_MODE")
		)
		(pad "6_7" smd circle
			(at 0.374904 0 270)
			(size 0 0)
			(layers "F.Cu" "F.Mask" "F.Paste")
			(net "P3V3_NIC0")
		)
		(pad "8" smd rect
			(at 0.499872 -0.999998)
			(size 0.254 0.7112)
			(layers "F.Cu" "F.Mask" "F.Paste")
			(net "P3V3_NIC0_CO_GATE")
		)
		(pad "9" smd rect
			(at 0 -0.999998)
			(size 0.254 0.7112)
			(layers "F.Cu" "F.Mask" "F.Paste")
			(net "P3V3_NIC0_CO_EN")
		)
		(pad "10" smd rect
			(at -0.499872 -0.999998)
			(size 0.254 0.7112)
			(layers "F.Cu" "F.Mask" "F.Paste")
			(net "P3V3_NIC0_CO_DV_DT")
		)
	)
	(footprint ""
		(layer "F.Cu")
		(at 105.688384 -170.951652 180)
		(property "Reference" "PC24"
			(at 0 0 180)
			(layer "F.SilkS")
			(hide yes)
			(effects
				(font
					(size 1.27 1.27)
				)
			)
		)
		(property "Value" ""
			(at 0 0 180)
			(layer "F.Fab")
			(effects
				(font
					(size 1.27 1.27)
				)
			)
		)
		(duplicate_pad_numbers_are_jumpers no)
		(fp_line
			(start 3.400044 3.400044)
			(end -2.146046 3.400044)
			(stroke
				(width 0.1524)
				(type default)
			)
			(layer "F.SilkS")
		)
		(fp_line
			(start 3.400044 0.9398)
			(end 3.400044 3.400044)
			(stroke
				(width 0.1524)
				(type default)
			)
			(layer "F.SilkS")
		)
		(fp_line
			(start 3.400044 -0.9398)
			(end 3.400044 -3.400044)
			(stroke
				(width 0.1524)
				(type default)
			)
			(layer "F.SilkS")
		)
		(fp_line
			(start 3.400044 -3.400044)
			(end -2.146046 -3.400044)
			(stroke
				(width 0.1524)
				(type default)
			)
			(layer "F.SilkS")
		)
		(fp_line
			(start -2.146046 3.400044)
			(end -3.400044 2.146046)
			(stroke
				(width 0.1524)
				(type default)
			)
			(layer "F.SilkS")
		)
		(fp_line
			(start -2.146046 -3.400044)
			(end -3.400044 -2.146046)
			(stroke
				(width 0.1524)
				(type default)
			)
			(layer "F.SilkS")
		)
		(fp_line
			(start -3.400044 2.146046)
			(end -3.400044 0.9398)
			(stroke
				(width 0.1524)
				(type default)
			)
			(layer "F.SilkS")
		)
		(fp_line
			(start -3.400044 -2.146046)
			(end -3.400044 -0.9398)
			(stroke
				(width 0.1524)
				(type default)
			)
			(layer "F.SilkS")
		)
		(fp_line
			(start 3.400044 3.400044)
			(end 3.400044 -3.400044)
			(stroke
				(width 0.1)
				(type default)
			)
			(layer "F.Fab")
		)
		(fp_line
			(start 3.400044 -3.400044)
			(end -3.400044 -3.400044)
			(stroke
				(width 0.1)
				(type default)
			)
			(layer "F.Fab")
		)
		(fp_line
			(start -3.400044 3.400044)
			(end 3.400044 3.400044)
			(stroke
				(width 0.1)
				(type default)
			)
			(layer "F.Fab")
		)
		(fp_line
			(start -3.400044 -3.400044)
			(end -3.400044 3.400044)
			(stroke
				(width 0.1)
				(type default)
			)
			(layer "F.Fab")
		)
		(pad "1" smd rect
			(at -2.70002 0 90)
			(size 1.6002 3.5052)
			(layers "F.Cu" "F.Mask" "F.Paste")
			(net "SW_P12V_P3V3_AUX_FLT")
		)
		(pad "2" smd rect
			(at 2.70002 0 90)
			(size 1.6002 3.5052)
			(layers "F.Cu" "F.Mask" "F.Paste")
			(net "GND")
		)
	)
	(footprint ""
		(layer "F.Cu")
		(at 134.5311 -123.903994 -90)
		(property "Reference" "PC477"
			(at 0 0 270)
			(layer "F.SilkS")
			(hide yes)
			(effects
				(font
					(size 1.27 1.27)
				)
			)
		)
		(property "Value" ""
			(at 0 0 270)
			(layer "F.Fab")
			(effects
				(font
					(size 1.27 1.27)
				)
			)
		)
		(duplicate_pad_numbers_are_jumpers no)
		(fp_line
			(start -1.524 0.762)
			(end -1.524 -0.762)
			(stroke
				(width 0.1524)
				(type default)
			)
			(layer "F.SilkS")
		)
		(fp_line
			(start 1.524 0.762)
			(end -1.524 0.762)
			(stroke
				(width 0.1524)
				(type default)
			)
			(layer "F.SilkS")
		)
		(fp_line
			(start -1.524 -0.762)
			(end 1.524 -0.762)
			(stroke
				(width 0.1524)
				(type default)
			)
			(layer "F.SilkS")
		)
		(fp_line
			(start 1.524 -0.762)
			(end 1.524 0.762)
			(stroke
				(width 0.1524)
				(type default)
			)
			(layer "F.SilkS")
		)
		(fp_line
			(start -1.1049 0.724916)
			(end 1.1049 0.724916)
			(stroke
				(width 0.1)
				(type default)
			)
			(layer "F.Fab")
		)
		(fp_line
			(start 1.1049 0.724916)
			(end 1.1049 -0.724916)
			(stroke
				(width 0.1)
				(type default)
			)
			(layer "F.Fab")
		)
		(fp_line
			(start -1.1049 -0.724916)
			(end -1.1049 0.724916)
			(stroke
				(width 0.1)
				(type default)
			)
			(layer "F.Fab")
		)
		(fp_line
			(start 1.1049 -0.724916)
			(end -1.1049 -0.724916)
			(stroke
				(width 0.1)
				(type default)
			)
			(layer "F.Fab")
		)
		(pad "1" smd rect
			(at -0.889 0 90)
			(size 1.016 1.27)
			(layers "F.Cu" "F.Mask" "F.Paste")
			(net "P3V3_NIC2")
		)
		(pad "2" smd rect
			(at 0.889 0 90)
			(size 1.016 1.27)
			(layers "F.Cu" "F.Mask" "F.Paste")
			(net "GND")
		)
	)
	(footprint ""
		(layer "F.Cu")
		(at 262.281924 -286.590232 180)
		(property "Reference" "C3409"
			(at 0 0 180)
			(layer "F.SilkS")
			(hide yes)
			(effects
				(font
					(size 1.27 1.27)
				)
			)
		)
		(property "Value" ""
			(at 0 0 180)
			(layer "F.Fab")
			(effects
				(font
					(size 1.27 1.27)
				)
			)
		)
		(duplicate_pad_numbers_are_jumpers no)
		(fp_line
			(start 1.2954 0.5842)
			(end -1.2954 0.5842)
			(stroke
				(width 0.1524)
				(type default)
			)
			(layer "F.SilkS")
		)
		(fp_line
			(start 1.2954 -0.5842)
			(end 1.2954 0.5842)
			(stroke
				(width 0.1524)
				(type default)
			)
			(layer "F.SilkS")
		)
		(fp_line
			(start -1.2954 0.5842)
			(end -1.2954 -0.5842)
			(stroke
				(width 0.1524)
				(type default)
			)
			(layer "F.SilkS")
		)
		(fp_line
			(start -1.2954 -0.5842)
			(end 1.2954 -0.5842)
			(stroke
				(width 0.1524)
				(type default)
			)
			(layer "F.SilkS")
		)
		(fp_line
			(start 1.1938 0.4064)
			(end 0.8636 0.4064)
			(stroke
				(width 0.1)
				(type default)
			)
			(layer "F.Fab")
		)
		(fp_line
			(start 1.1938 -0.4064)
			(end 1.1938 0.4064)
			(stroke
				(width 0.1)
				(type default)
			)
			(layer "F.Fab")
		)
		(fp_line
			(start 0.8636 0.4572)
			(end -0.8636 0.4572)
			(stroke
				(width 0.1)
				(type default)
			)
			(layer "F.Fab")
		)
		(fp_line
			(start 0.8636 0.4064)
			(end 0.8636 0.4572)
			(stroke
				(width 0.1)
				(type default)
			)
			(layer "F.Fab")
		)
		(fp_line
			(start 0.8636 -0.4064)
			(end 1.1938 -0.4064)
			(stroke
				(width 0.1)
				(type default)
			)
			(layer "F.Fab")
		)
		(fp_line
			(start 0.8636 -0.4572)
			(end 0.8636 -0.4064)
			(stroke
				(width 0.1)
				(type default)
			)
			(layer "F.Fab")
		)
		(fp_line
			(start -0.8636 0.4572)
			(end -0.8636 0.4064)
			(stroke
				(width 0.1)
				(type default)
			)
			(layer "F.Fab")
		)
		(fp_line
			(start -0.8636 0.4064)
			(end -1.1938 0.4064)
			(stroke
				(width 0.1)
				(type default)
			)
			(layer "F.Fab")
		)
		(fp_line
			(start -0.8636 -0.4064)
			(end -0.8636 -0.4572)
			(stroke
				(width 0.1)
				(type default)
			)
			(layer "F.Fab")
		)
		(fp_line
			(start -0.8636 -0.4572)
			(end 0.8636 -0.4572)
			(stroke
				(width 0.1)
				(type default)
			)
			(layer "F.Fab")
		)
		(fp_line
			(start -1.1938 0.4064)
			(end -1.1938 -0.4064)
			(stroke
				(width 0.1)
				(type default)
			)
			(layer "F.Fab")
		)
		(fp_line
			(start -1.1938 -0.4064)
			(end -0.8636 -0.4064)
			(stroke
				(width 0.1)
				(type default)
			)
			(layer "F.Fab")
		)
		(pad "1" smd rect
			(at -0.7366 0 90)
			(size 0.7112 0.8128)
			(layers "F.Cu" "F.Mask" "F.Paste")
			(net "PCEPLL6_VDDA18_PEX2_R")
		)
		(pad "2" smd rect
			(at 0.7366 0 90)
			(size 0.7112 0.8128)
			(layers "F.Cu" "F.Mask" "F.Paste")
			(net "GND")
		)
	)
	(footprint ""
		(layer "F.Cu")
		(at 91.168982 -123.067318 90)
		(property "Reference" "PC465"
			(at 0 0 90)
			(layer "F.SilkS")
			(hide yes)
			(effects
				(font
					(size 1.27 1.27)
				)
			)
		)
		(property "Value" ""
			(at 0 0 90)
			(layer "F.Fab")
			(effects
				(font
					(size 1.27 1.27)
				)
			)
		)
		(duplicate_pad_numbers_are_jumpers no)
		(fp_line
			(start 1.524 -0.762)
			(end 1.524 0.762)
			(stroke
				(width 0.1524)
				(type default)
			)
			(layer "F.SilkS")
		)
		(fp_line
			(start -1.524 -0.762)
			(end 1.524 -0.762)
			(stroke
				(width 0.1524)
				(type default)
			)
			(layer "F.SilkS")
		)
		(fp_line
			(start 1.524 0.762)
			(end -1.524 0.762)
			(stroke
				(width 0.1524)
				(type default)
			)
			(layer "F.SilkS")
		)
		(fp_line
			(start -1.524 0.762)
			(end -1.524 -0.762)
			(stroke
				(width 0.1524)
				(type default)
			)
			(layer "F.SilkS")
		)
		(fp_line
			(start 1.1049 -0.724916)
			(end -1.1049 -0.724916)
			(stroke
				(width 0.1)
				(type default)
			)
			(layer "F.Fab")
		)
		(fp_line
			(start -1.1049 -0.724916)
			(end -1.1049 0.724916)
			(stroke
				(width 0.1)
				(type default)
			)
			(layer "F.Fab")
		)
		(fp_line
			(start 1.1049 0.724916)
			(end 1.1049 -0.724916)
			(stroke
				(width 0.1)
				(type default)
			)
			(layer "F.Fab")
		)
		(fp_line
			(start -1.1049 0.724916)
			(end 1.1049 0.724916)
			(stroke
				(width 0.1)
				(type default)
			)
			(layer "F.Fab")
		)
		(pad "1" smd rect
			(at -0.889 0 270)
			(size 1.016 1.27)
			(layers "F.Cu" "F.Mask" "F.Paste")
			(net "P3V3_NIC1")
		)
		(pad "2" smd rect
			(at 0.889 0 270)
			(size 1.016 1.27)
			(layers "F.Cu" "F.Mask" "F.Paste")
			(net "GND")
		)
	)
	(footprint ""
		(layer "F.Cu")
		(at 225.738944 -98.36912 -90)
		(property "Reference" "PC469"
			(at 0 0 270)
			(layer "F.SilkS")
			(hide yes)
			(effects
				(font
					(size 1.27 1.27)
				)
			)
		)
		(property "Value" ""
			(at 0 0 270)
			(layer "F.Fab")
			(effects
				(font
					(size 1.27 1.27)
				)
			)
		)
		(duplicate_pad_numbers_are_jumpers no)
		(fp_line
			(start -0.7874 0.4064)
			(end -0.7874 -0.4064)
			(stroke
				(width 0.1524)
				(type default)
			)
			(layer "F.SilkS")
		)
		(fp_line
			(start 0.7874 0.4064)
			(end -0.7874 0.4064)
			(stroke
				(width 0.1524)
				(type default)
			)
			(layer "F.SilkS")
		)
		(fp_line
			(start -0.7874 -0.4064)
			(end 0.7874 -0.4064)
			(stroke
				(width 0.1524)
				(type default)
			)
			(layer "F.SilkS")
		)
		(fp_line
			(start 0.7874 -0.4064)
			(end 0.7874 0.4064)
			(stroke
				(width 0.1524)
				(type default)
			)
			(layer "F.SilkS")
		)
		(fp_line
			(start -0.67945 0.3048)
			(end -0.67945 -0.305054)
			(stroke
				(width 0.1)
				(type default)
			)
			(layer "F.Fab")
		)
		(fp_line
			(start -0.12065 0.3048)
			(end -0.67945 0.3048)
			(stroke
				(width 0.1)
				(type default)
			)
			(layer "F.Fab")
		)
		(fp_line
			(start 0.120396 0.3048)
			(end 0.120396 0.2794)
			(stroke
				(width 0.1)
				(type default)
			)
			(layer "F.Fab")
		)
		(fp_line
			(start 0.67945 0.3048)
			(end 0.120396 0.3048)
			(stroke
				(width 0.1)
				(type default)
			)
			(layer "F.Fab")
		)
		(fp_line
			(start -0.12065 0.2794)
			(end -0.12065 0.3048)
			(stroke
				(width 0.1)
				(type default)
			)
			(layer "F.Fab")
		)
		(fp_line
			(start 0.120396 0.2794)
			(end -0.12065 0.2794)
			(stroke
				(width 0.1)
				(type default)
			)
			(layer "F.Fab")
		)
		(fp_line
			(start -0.12065 -0.2794)
			(end 0.12065 -0.2794)
			(stroke
				(width 0.1)
				(type default)
			)
			(layer "F.Fab")
		)
		(fp_line
			(start 0.12065 -0.2794)
			(end 0.12065 -0.3048)
			(stroke
				(width 0.1)
				(type default)
			)
			(layer "F.Fab")
		)
		(fp_line
			(start 0.12065 -0.3048)
			(end 0.67945 -0.3048)
			(stroke
				(width 0.1)
				(type default)
			)
			(layer "F.Fab")
		)
		(fp_line
			(start 0.67945 -0.3048)
			(end 0.67945 0.3048)
			(stroke
				(width 0.1)
				(type default)
			)
			(layer "F.Fab")
		)
		(fp_line
			(start -0.67945 -0.305054)
			(end -0.12065 -0.305054)
			(stroke
				(width 0.1)
				(type default)
			)
			(layer "F.Fab")
		)
		(fp_line
			(start -0.12065 -0.305054)
			(end -0.12065 -0.2794)
			(stroke
				(width 0.1)
				(type default)
			)
			(layer "F.Fab")
		)
		(pad "1" smd circle
			(at -0.40005 0 270)
			(size 0 0)
			(layers "F.Cu" "F.Mask" "F.Paste")
			(net "P5V_AUX")
		)
		(pad "2" smd circle
			(at 0.40005 0 270)
			(size 0 0)
			(layers "F.Cu" "F.Mask" "F.Paste")
			(net "GND")
		)
	)
	(footprint ""
		(layer "F.Cu")
		(at 432.80203 -141.150848 -90)
		(property "Reference" "U44"
			(at 2.722118 0.13843 0)
			(unlocked yes)
			(layer "F.SilkS")
			(effects
				(font
					(size 0.7874 0.5842)
					(thickness 0.1524)
				)
			)
		)
		(property "Value" ""
			(at 0 0 270)
			(layer "F.Fab")
			(effects
				(font
					(size 1.27 1.27)
				)
			)
		)
		(duplicate_pad_numbers_are_jumpers no)
		(fp_line
			(start -1.949958 1.610106)
			(end -1.949958 -1.610106)
			(stroke
				(width 0.1524)
				(type default)
			)
			(layer "F.SilkS")
		)
		(fp_line
			(start 1.949958 1.610106)
			(end -1.949958 1.610106)
			(stroke
				(width 0.1524)
				(type default)
			)
			(layer "F.SilkS")
		)
		(fp_line
			(start 1.949958 -1.560068)
			(end 1.949958 1.610106)
			(stroke
				(width 0.1524)
				(type default)
			)
			(layer "F.SilkS")
		)
		(fp_line
			(start -1.949958 -1.610106)
			(end 1.949958 -1.610106)
			(stroke
				(width 0.1524)
				(type default)
			)
			(layer "F.SilkS")
		)
		(fp_line
			(start -0.750062 1.560068)
			(end -0.750062 -1.560068)
			(stroke
				(width 0.1)
				(type default)
			)
			(layer "F.Fab")
		)
		(fp_line
			(start 0.750062 1.560068)
			(end -0.750062 1.560068)
			(stroke
				(width 0.1)
				(type default)
			)
			(layer "F.Fab")
		)
		(fp_line
			(start -0.750062 -1.560068)
			(end 0.750062 -1.560068)
			(stroke
				(width 0.1)
				(type default)
			)
			(layer "F.Fab")
		)
		(fp_line
			(start 0.750062 -1.560068)
			(end 0.750062 1.560068)
			(stroke
				(width 0.1)
				(type default)
			)
			(layer "F.Fab")
		)
		(pad "D" smd rect
			(at 1.100074 0 180)
			(size 1.016 1.4224)
			(layers "F.Cu" "F.Mask" "F.Paste")
			(net "HP_NIC7_EN")
		)
		(pad "G" smd rect
			(at -1.100074 -0.94996 180)
			(size 1.016 1.4224)
			(layers "F.Cu" "F.Mask" "F.Paste")
			(net "PRSNT_NIC7_R_N")
		)
		(pad "S" smd rect
			(at -1.100074 0.94996 180)
			(size 1.016 1.4224)
			(layers "F.Cu" "F.Mask" "F.Paste")
			(net "GND")
		)
	)
)
